(kicad_pcb
	(version 20260206)
	(generator "pcbnew")
	(generator_version "10.0")
	(general
		(thickness 1.6)
		(legacy_teardrops no)
	)
	(paper "A4")
	(title_block
		(title "01162023_DA0F0TEBIF0_F0T_Expander_BD_F_brd_V02_OCP.brd")
		(comment 1 "Grand Teton / footprints 3251-3255 of 9728")
	)
	(layers
		(0 "F.Cu" signal "TOP")
		(4 "In1.Cu" signal "GND")
		(6 "In2.Cu" signal "VCC")
		(8 "In3.Cu" signal "VCC1")
		(10 "In4.Cu" signal "GND1")
		(12 "In5.Cu" signal "IN1")
		(14 "In6.Cu" signal "GND2")
		(16 "In7.Cu" signal "IN2")
		(18 "In8.Cu" signal "GND3")
		(20 "In9.Cu" signal "IN3")
		(22 "In10.Cu" signal "GND4")
		(24 "In11.Cu" signal "IN4")
		(26 "In12.Cu" signal "GND5")
		(28 "In13.Cu" signal "IN5")
		(30 "In14.Cu" signal "GND6")
		(32 "In15.Cu" signal "IN6")
		(34 "In16.Cu" signal "GND7")
		(2 "B.Cu" signal "BOTTOM")
		(9 "F.Adhes" user "F.Adhesive")
		(11 "B.Adhes" user "B.Adhesive")
		(13 "F.Paste" user "Package Geometry/Pastemask Top")
		(15 "B.Paste" user "Package Geometry/Pastemask Bottom")
		(5 "F.SilkS" user "Ref Des/Silkscreen Top")
		(7 "B.SilkS" user "Ref Des/Silkscreen Bottom")
		(1 "F.Mask" user "Board Geometry/Soldermask Top")
		(3 "B.Mask" user "Board Geometry/Soldermask Bottom")
		(17 "Dwgs.User" user "User.Drawings")
		(19 "Cmts.User" user "User.Comments")
		(21 "Eco1.User" user "User.Eco1")
		(23 "Eco2.User" user "User.Eco2")
		(25 "Edge.Cuts" user "Board Geometry/Outline")
		(27 "Margin" user)
		(31 "F.CrtYd" user "Package Geometry/Place Bound Top")
		(29 "B.CrtYd" user "Package Geometry/Place Bound Bottom")
		(35 "F.Fab" user "Ref Des/Assembly Top")
		(33 "B.Fab" user "Ref Des/Assembly Bottom")
	)
	(footprint ""
		(layer "F.Cu")
		(at 286.541718 -27.006296 -90)
		(property "Reference" "PR7120"
			(at 0 0 270)
			(layer "F.SilkS")
			(hide yes)
			(effects
				(font
					(size 1.27 1.27)
				)
			)
		)
		(property "Value" ""
			(at 0 0 270)
			(layer "F.Fab")
			(effects
				(font
					(size 1.27 1.27)
				)
			)
		)
		(duplicate_pad_numbers_are_jumpers no)
		(fp_line
			(start -0.7874 0.4064)
			(end -0.7874 -0.4064)
			(stroke
				(width 0.1524)
				(type default)
			)
			(layer "F.SilkS")
		)
		(fp_line
			(start 0.7874 0.4064)
			(end -0.7874 0.4064)
			(stroke
				(width 0.1524)
				(type default)
			)
			(layer "F.SilkS")
		)
		(fp_line
			(start -0.7874 -0.4064)
			(end 0.7874 -0.4064)
			(stroke
				(width 0.1524)
				(type default)
			)
			(layer "F.SilkS")
		)
		(fp_line
			(start 0.7874 -0.4064)
			(end 0.7874 0.4064)
			(stroke
				(width 0.1524)
				(type default)
			)
			(layer "F.SilkS")
		)
		(fp_line
			(start -0.67945 0.3048)
			(end -0.67945 -0.305054)
			(stroke
				(width 0.1)
				(type default)
			)
			(layer "F.Fab")
		)
		(fp_line
			(start -0.12065 0.3048)
			(end -0.67945 0.3048)
			(stroke
				(width 0.1)
				(type default)
			)
			(layer "F.Fab")
		)
		(fp_line
			(start 0.120396 0.3048)
			(end 0.120396 0.2794)
			(stroke
				(width 0.1)
				(type default)
			)
			(layer "F.Fab")
		)
		(fp_line
			(start 0.67945 0.3048)
			(end 0.120396 0.3048)
			(stroke
				(width 0.1)
				(type default)
			)
			(layer "F.Fab")
		)
		(fp_line
			(start -0.12065 0.2794)
			(end -0.12065 0.3048)
			(stroke
				(width 0.1)
				(type default)
			)
			(layer "F.Fab")
		)
		(fp_line
			(start 0.120396 0.2794)
			(end -0.12065 0.2794)
			(stroke
				(width 0.1)
				(type default)
			)
			(layer "F.Fab")
		)
		(fp_line
			(start -0.12065 -0.2794)
			(end 0.12065 -0.2794)
			(stroke
				(width 0.1)
				(type default)
			)
			(layer "F.Fab")
		)
		(fp_line
			(start 0.12065 -0.2794)
			(end 0.12065 -0.3048)
			(stroke
				(width 0.1)
				(type default)
			)
			(layer "F.Fab")
		)
		(fp_line
			(start 0.12065 -0.3048)
			(end 0.67945 -0.3048)
			(stroke
				(width 0.1)
				(type default)
			)
			(layer "F.Fab")
		)
		(fp_line
			(start 0.67945 -0.3048)
			(end 0.67945 0.3048)
			(stroke
				(width 0.1)
				(type default)
			)
			(layer "F.Fab")
		)
		(fp_line
			(start -0.67945 -0.305054)
			(end -0.12065 -0.305054)
			(stroke
				(width 0.1)
				(type default)
			)
			(layer "F.Fab")
		)
		(fp_line
			(start -0.12065 -0.305054)
			(end -0.12065 -0.2794)
			(stroke
				(width 0.1)
				(type default)
			)
			(layer "F.Fab")
		)
		(pad "1" smd circle
			(at -0.40005 0 270)
			(size 0 0)
			(layers "F.Cu" "F.Mask" "F.Paste")
			(net "P3V3_SSD10_CO_ILIMIT")
		)
		(pad "2" smd circle
			(at 0.40005 0 270)
			(size 0 0)
			(layers "F.Cu" "F.Mask" "F.Paste")
			(net "GND")
		)
	)
	(footprint ""
		(layer "F.Cu")
		(at 381.587756 -285.218632)
		(property "Reference" "C3580"
			(at 0 0 0)
			(layer "F.SilkS")
			(hide yes)
			(effects
				(font
					(size 1.27 1.27)
				)
			)
		)
		(property "Value" ""
			(at 0 0 0)
			(layer "F.Fab")
			(effects
				(font
					(size 1.27 1.27)
				)
			)
		)
		(duplicate_pad_numbers_are_jumpers no)
		(fp_line
			(start -1.2954 -0.5842)
			(end 1.2954 -0.5842)
			(stroke
				(width 0.1524)
				(type default)
			)
			(layer "F.SilkS")
		)
		(fp_line
			(start -1.2954 0.5842)
			(end -1.2954 -0.5842)
			(stroke
				(width 0.1524)
				(type default)
			)
			(layer "F.SilkS")
		)
		(fp_line
			(start 1.2954 -0.5842)
			(end 1.2954 0.5842)
			(stroke
				(width 0.1524)
				(type default)
			)
			(layer "F.SilkS")
		)
		(fp_line
			(start 1.2954 0.5842)
			(end -1.2954 0.5842)
			(stroke
				(width 0.1524)
				(type default)
			)
			(layer "F.SilkS")
		)
		(fp_line
			(start -1.1938 -0.4064)
			(end -0.8636 -0.4064)
			(stroke
				(width 0.1)
				(type default)
			)
			(layer "F.Fab")
		)
		(fp_line
			(start -1.1938 0.4064)
			(end -1.1938 -0.4064)
			(stroke
				(width 0.1)
				(type default)
			)
			(layer "F.Fab")
		)
		(fp_line
			(start -0.8636 -0.4572)
			(end 0.8636 -0.4572)
			(stroke
				(width 0.1)
				(type default)
			)
			(layer "F.Fab")
		)
		(fp_line
			(start -0.8636 -0.4064)
			(end -0.8636 -0.4572)
			(stroke
				(width 0.1)
				(type default)
			)
			(layer "F.Fab")
		)
		(fp_line
			(start -0.8636 0.4064)
			(end -1.1938 0.4064)
			(stroke
				(width 0.1)
				(type default)
			)
			(layer "F.Fab")
		)
		(fp_line
			(start -0.8636 0.4572)
			(end -0.8636 0.4064)
			(stroke
				(width 0.1)
				(type default)
			)
			(layer "F.Fab")
		)
		(fp_line
			(start 0.8636 -0.4572)
			(end 0.8636 -0.4064)
			(stroke
				(width 0.1)
				(type default)
			)
			(layer "F.Fab")
		)
		(fp_line
			(start 0.8636 -0.4064)
			(end 1.1938 -0.4064)
			(stroke
				(width 0.1)
				(type default)
			)
			(layer "F.Fab")
		)
		(fp_line
			(start 0.8636 0.4064)
			(end 0.8636 0.4572)
			(stroke
				(width 0.1)
				(type default)
			)
			(layer "F.Fab")
		)
		(fp_line
			(start 0.8636 0.4572)
			(end -0.8636 0.4572)
			(stroke
				(width 0.1)
				(type default)
			)
			(layer "F.Fab")
		)
		(fp_line
			(start 1.1938 -0.4064)
			(end 1.1938 0.4064)
			(stroke
				(width 0.1)
				(type default)
			)
			(layer "F.Fab")
		)
		(fp_line
			(start 1.1938 0.4064)
			(end 0.8636 0.4064)
			(stroke
				(width 0.1)
				(type default)
			)
			(layer "F.Fab")
		)
		(pad "1" smd rect
			(at -0.7366 0 270)
			(size 0.7112 0.8128)
			(layers "F.Cu" "F.Mask" "F.Paste")
			(net "PCEPLL7_VDDA18_PEX3")
		)
		(pad "2" smd rect
			(at 0.7366 0 270)
			(size 0.7112 0.8128)
			(layers "F.Cu" "F.Mask" "F.Paste")
			(net "GND")
		)
	)
	(footprint ""
		(layer "F.Cu")
		(at 195.414646 -81.36001 -90)
		(property "Reference" "R204"
			(at 0 0 270)
			(layer "F.SilkS")
			(hide yes)
			(effects
				(font
					(size 1.27 1.27)
				)
			)
		)
		(property "Value" ""
			(at 0 0 270)
			(layer "F.Fab")
			(effects
				(font
					(size 1.27 1.27)
				)
			)
		)
		(duplicate_pad_numbers_are_jumpers no)
		(fp_line
			(start -0.7874 0.4064)
			(end -0.7874 -0.4064)
			(stroke
				(width 0.1524)
				(type default)
			)
			(layer "F.SilkS")
		)
		(fp_line
			(start 0.7874 0.4064)
			(end -0.7874 0.4064)
			(stroke
				(width 0.1524)
				(type default)
			)
			(layer "F.SilkS")
		)
		(fp_line
			(start -0.7874 -0.4064)
			(end 0.7874 -0.4064)
			(stroke
				(width 0.1524)
				(type default)
			)
			(layer "F.SilkS")
		)
		(fp_line
			(start 0.7874 -0.4064)
			(end 0.7874 0.4064)
			(stroke
				(width 0.1524)
				(type default)
			)
			(layer "F.SilkS")
		)
		(fp_line
			(start -0.67945 0.3048)
			(end -0.67945 -0.305054)
			(stroke
				(width 0.1)
				(type default)
			)
			(layer "F.Fab")
		)
		(fp_line
			(start -0.12065 0.3048)
			(end -0.67945 0.3048)
			(stroke
				(width 0.1)
				(type default)
			)
			(layer "F.Fab")
		)
		(fp_line
			(start 0.120396 0.3048)
			(end 0.120396 0.2794)
			(stroke
				(width 0.1)
				(type default)
			)
			(layer "F.Fab")
		)
		(fp_line
			(start 0.67945 0.3048)
			(end 0.120396 0.3048)
			(stroke
				(width 0.1)
				(type default)
			)
			(layer "F.Fab")
		)
		(fp_line
			(start -0.12065 0.2794)
			(end -0.12065 0.3048)
			(stroke
				(width 0.1)
				(type default)
			)
			(layer "F.Fab")
		)
		(fp_line
			(start 0.120396 0.2794)
			(end -0.12065 0.2794)
			(stroke
				(width 0.1)
				(type default)
			)
			(layer "F.Fab")
		)
		(fp_line
			(start -0.12065 -0.2794)
			(end 0.12065 -0.2794)
			(stroke
				(width 0.1)
				(type default)
			)
			(layer "F.Fab")
		)
		(fp_line
			(start 0.12065 -0.2794)
			(end 0.12065 -0.3048)
			(stroke
				(width 0.1)
				(type default)
			)
			(layer "F.Fab")
		)
		(fp_line
			(start 0.12065 -0.3048)
			(end 0.67945 -0.3048)
			(stroke
				(width 0.1)
				(type default)
			)
			(layer "F.Fab")
		)
		(fp_line
			(start 0.67945 -0.3048)
			(end 0.67945 0.3048)
			(stroke
				(width 0.1)
				(type default)
			)
			(layer "F.Fab")
		)
		(fp_line
			(start -0.67945 -0.305054)
			(end -0.12065 -0.305054)
			(stroke
				(width 0.1)
				(type default)
			)
			(layer "F.Fab")
		)
		(fp_line
			(start -0.12065 -0.305054)
			(end -0.12065 -0.2794)
			(stroke
				(width 0.1)
				(type default)
			)
			(layer "F.Fab")
		)
		(pad "1" smd circle
			(at -0.40005 0 270)
			(size 0 0)
			(layers "F.Cu" "F.Mask" "F.Paste")
			(net "HP_NIC3_PWRGD_R")
		)
		(pad "2" smd circle
			(at 0.40005 0 270)
			(size 0 0)
			(layers "F.Cu" "F.Mask" "F.Paste")
			(net "HP_NIC3_PWRGD")
		)
	)
	(footprint ""
		(layer "F.Cu")
		(at 123.71324 -137.344404 180)
		(property "Reference" "PR201"
			(at 0 0 180)
			(layer "F.SilkS")
			(hide yes)
			(effects
				(font
					(size 1.27 1.27)
				)
			)
		)
		(property "Value" ""
			(at 0 0 180)
			(layer "F.Fab")
			(effects
				(font
					(size 1.27 1.27)
				)
			)
		)
		(duplicate_pad_numbers_are_jumpers no)
		(fp_line
			(start 0.7874 0.4064)
			(end -0.7874 0.4064)
			(stroke
				(width 0.1524)
				(type default)
			)
			(layer "F.SilkS")
		)
		(fp_line
			(start 0.7874 -0.4064)
			(end 0.7874 0.4064)
			(stroke
				(width 0.1524)
				(type default)
			)
			(layer "F.SilkS")
		)
		(fp_line
			(start -0.7874 0.4064)
			(end -0.7874 -0.4064)
			(stroke
				(width 0.1524)
				(type default)
			)
			(layer "F.SilkS")
		)
		(fp_line
			(start -0.7874 -0.4064)
			(end 0.7874 -0.4064)
			(stroke
				(width 0.1524)
				(type default)
			)
			(layer "F.SilkS")
		)
		(fp_line
			(start 0.67945 0.3048)
			(end 0.120396 0.3048)
			(stroke
				(width 0.1)
				(type default)
			)
			(layer "F.Fab")
		)
		(fp_line
			(start 0.67945 -0.3048)
			(end 0.67945 0.3048)
			(stroke
				(width 0.1)
				(type default)
			)
			(layer "F.Fab")
		)
		(fp_line
			(start 0.12065 -0.2794)
			(end 0.12065 -0.3048)
			(stroke
				(width 0.1)
				(type default)
			)
			(layer "F.Fab")
		)
		(fp_line
			(start 0.12065 -0.3048)
			(end 0.67945 -0.3048)
			(stroke
				(width 0.1)
				(type default)
			)
			(layer "F.Fab")
		)
		(fp_line
			(start 0.120396 0.3048)
			(end 0.120396 0.2794)
			(stroke
				(width 0.1)
				(type default)
			)
			(layer "F.Fab")
		)
		(fp_line
			(start 0.120396 0.2794)
			(end -0.12065 0.2794)
			(stroke
				(width 0.1)
				(type default)
			)
			(layer "F.Fab")
		)
		(fp_line
			(start -0.12065 0.3048)
			(end -0.67945 0.3048)
			(stroke
				(width 0.1)
				(type default)
			)
			(layer "F.Fab")
		)
		(fp_line
			(start -0.12065 0.2794)
			(end -0.12065 0.3048)
			(stroke
				(width 0.1)
				(type default)
			)
			(layer "F.Fab")
		)
		(fp_line
			(start -0.12065 -0.2794)
			(end 0.12065 -0.2794)
			(stroke
				(width 0.1)
				(type default)
			)
			(layer "F.Fab")
		)
		(fp_line
			(start -0.12065 -0.305054)
			(end -0.12065 -0.2794)
			(stroke
				(width 0.1)
				(type default)
			)
			(layer "F.Fab")
		)
		(fp_line
			(start -0.67945 0.3048)
			(end -0.67945 -0.305054)
			(stroke
				(width 0.1)
				(type default)
			)
			(layer "F.Fab")
		)
		(fp_line
			(start -0.67945 -0.305054)
			(end -0.12065 -0.305054)
			(stroke
				(width 0.1)
				(type default)
			)
			(layer "F.Fab")
		)
		(pad "1" smd circle
			(at -0.40005 0 180)
			(size 0 0)
			(layers "F.Cu" "F.Mask" "F.Paste")
			(net "P12V_NIC2_OCP")
		)
		(pad "2" smd circle
			(at 0.40005 0 180)
			(size 0 0)
			(layers "F.Cu" "F.Mask" "F.Paste")
			(net "GND")
		)
	)
	(footprint ""
		(layer "F.Cu")
		(at 122.630692 -284.8991 180)
		(property "Reference" "PU9"
			(at -15.980918 -1.567688 90)
			(unlocked yes)
			(layer "F.SilkS")
			(effects
				(font
					(size 0.7874 0.5842)
					(thickness 0.1524)
				)
			)
		)
		(property "Value" ""
			(at 0 0 180)
			(layer "F.Fab")
			(effects
				(font
					(size 1.27 1.27)
				)
			)
		)
		(duplicate_pad_numbers_are_jumpers no)
		(fp_line
			(start 2.500122 2.999994)
			(end 2.2987 2.999994)
			(stroke
				(width 0.1524)
				(type default)
			)
			(layer "F.SilkS")
		)
		(fp_line
			(start 2.500122 2.339594)
			(end 2.500122 2.999994)
			(stroke
				(width 0.1524)
				(type default)
			)
			(layer "F.SilkS")
		)
		(fp_line
			(start 2.500122 -2.999994)
			(end 2.500122 -2.44348)
			(stroke
				(width 0.1524)
				(type default)
			)
			(layer "F.SilkS")
		)
		(fp_line
			(start 2.31394 -2.999994)
			(end 2.500122 -2.999994)
			(stroke
				(width 0.1524)
				(type default)
			)
			(layer "F.SilkS")
		)
		(fp_line
			(start -2.2987 2.999994)
			(end -2.500122 2.999994)
			(stroke
				(width 0.1524)
				(type default)
			)
			(layer "F.SilkS")
		)
		(fp_line
			(start -2.500122 2.999994)
			(end -2.500122 2.339594)
			(stroke
				(width 0.1524)
				(type default)
			)
			(layer "F.SilkS")
		)
		(fp_line
			(start -2.500122 0.6604)
			(end -2.500122 0.229108)
			(stroke
				(width 0.1524)
				(type default)
			)
			(layer "F.SilkS")
		)
		(fp_line
			(start -2.500122 -2.529078)
			(end -2.500122 -2.999994)
			(stroke
				(width 0.1524)
				(type default)
			)
			(layer "F.SilkS")
		)
		(fp_line
			(start -2.500122 -2.999994)
			(end -2.24409 -2.999994)
			(stroke
				(width 0.1524)
				(type default)
			)
			(layer "F.SilkS")
		)
		(fp_poly
			(pts
				(xy -2.347722 -3.580384) (xy -3.363722 -3.580384) (xy -2.855722 -2.564384)
			)
			(stroke
				(width 0)
				(type default)
			)
			(fill yes)
			(layer "F.SilkS")
		)
		(fp_line
			(start 2.500122 2.999994)
			(end -2.500122 2.999994)
			(stroke
				(width 0.1)
				(type default)
			)
			(layer "F.Fab")
		)
		(fp_line
			(start 2.500122 -2.999994)
			(end 2.500122 2.999994)
			(stroke
				(width 0.1)
				(type default)
			)
			(layer "F.Fab")
		)
		(fp_line
			(start -2.500122 2.999994)
			(end -2.500122 -2.999994)
			(stroke
				(width 0.1)
				(type default)
			)
			(layer "F.Fab")
		)
		(fp_line
			(start -2.500122 -2.999994)
			(end 2.500122 -2.999994)
			(stroke
				(width 0.1)
				(type default)
			)
			(layer "F.Fab")
		)
		(fp_poly
			(pts
				(xy -4.218432 -2.783078) (xy -4.218432 -1.767078) (xy -3.202432 -2.275078)
			)
			(stroke
				(width 0)
				(type default)
			)
			(fill yes)
			(layer "F.Fab")
		)
		(pad "1" smd rect
			(at -2.400046 -2.275078 270)
			(size 0.2286 0.6096)
			(layers "F.Cu" "F.Mask" "F.Paste")
			(net "SW_P0V8_PEX1_VOS1")
		)
		(pad "2" smd rect
			(at -2.400046 -1.82499 270)
			(size 0.2286 0.6096)
			(layers "F.Cu" "F.Mask" "F.Paste")
			(net "GND")
		)
		(pad "3" smd rect
			(at -2.400046 -1.374902 270)
			(size 0.2286 0.6096)
			(layers "F.Cu" "F.Mask" "F.Paste")
			(net "P0V8_PEX1_VCC1")
		)
		(pad "4" smd rect
			(at -2.400046 -0.925068 270)
			(size 0.2286 0.6096)
			(layers "F.Cu" "F.Mask" "F.Paste")
			(net "P0V8_PEX1_PVCC")
		)
		(pad "5" smd rect
			(at -2.400046 -0.47498 270)
			(size 0.2286 0.6096)
			(layers "F.Cu" "F.Mask" "F.Paste")
			(net "GND")
		)
		(pad "6" smd rect
			(at -2.400046 -0.024892 270)
			(size 0.2286 0.6096)
			(layers "F.Cu" "F.Mask" "F.Paste")
			(net "NC_P0V8_PEX1_PH1_NC1")
		)
		(pad "7_9-20_24" smd circle
			(at 0 1.150112 270)
			(size 0 0)
			(layers "F.Cu" "F.Mask" "F.Paste")
			(net "GND")
		)
		(pad "10_19" smd rect
			(at 0 2.899918 270)
			(size 0.6096 4.318)
			(layers "F.Cu" "F.Mask" "F.Paste")
			(net "SW_P0V8_PEX1_PH1")
		)
		(pad "25_29" smd rect
			(at 1.549908 -1.279906 90)
			(size 2.0574 2.3114)
			(layers "F.Cu" "F.Mask" "F.Paste")
			(net "SW_P12V_P0V8_PEX1_FLT")
		)
		(pad "30" smd rect
			(at 2.05994 -2.899918 180)
			(size 0.2286 0.6096)
			(layers "F.Cu" "F.Mask" "F.Paste")
			(net "SW_P12V_P0V8_PEX1_FLT")
		)
		(pad "31" smd rect
			(at 1.610106 -2.899918 180)
			(size 0.2286 0.6096)
			(layers "F.Cu" "F.Mask" "F.Paste")
			(net "NC_P0V8_PEX1_PH1_NC3")
		)
		(pad "32" smd rect
			(at 1.160018 -2.899918 180)
			(size 0.2286 0.6096)
			(layers "F.Cu" "F.Mask" "F.Paste")
			(net "SW_P0V8_PEX1_PHASE1")
		)
		(pad "33" smd rect
			(at 0.70993 -2.899918 180)
			(size 0.2286 0.6096)
			(layers "F.Cu" "F.Mask" "F.Paste")
			(net "SW_P0V8_PEX1_BOOT1")
		)
		(pad "34" smd rect
			(at 0.260096 -2.899918 180)
			(size 0.2286 0.6096)
			(layers "F.Cu" "F.Mask" "F.Paste")
			(net "P0V8_PEX1_PWM1")
		)
		(pad "35" smd rect
			(at -0.189992 -2.899918 180)
			(size 0.2286 0.6096)
			(layers "F.Cu" "F.Mask" "F.Paste")
			(net "P0V8_PEX0_EN3")
		)
		(pad "36" smd rect
			(at -0.64008 -2.899918 180)
			(size 0.2286 0.6096)
			(layers "F.Cu" "F.Mask" "F.Paste")
			(net "P0V8_PEX1_TSEN")
		)
		(pad "37" smd rect
			(at -1.089914 -2.899918 180)
			(size 0.2286 0.6096)
			(layers "F.Cu" "F.Mask" "F.Paste")
			(net "P0V8_PEX1_LSET1")
		)
		(pad "38" smd rect
			(at -1.540002 -2.899918 180)
			(size 0.2286 0.6096)
			(layers "F.Cu" "F.Mask" "F.Paste")
			(net "P0V8_PEX1_ISEN1")
		)
		(pad "39" smd rect
			(at -1.99009 -2.899918 180)
			(size 0.2286 0.6096)
			(layers "F.Cu" "F.Mask" "F.Paste")
			(net "P0V8_PEX0_VREF")
		)
		(pad "40" smd rect
			(at -0.87503 -1.27508 180)
			(size 1.7526 1.9558)
			(layers "F.Cu" "F.Mask" "F.Paste")
			(net "GND")
		)
		(pad "41" smd rect
			(at -1.525016 0.249936 90)
			(size 0.3048 0.4572)
			(layers "F.Cu" "F.Mask" "F.Paste")
			(net "NC_P0V8_PEX1_PH1_NC2")
		)
		(zone
			(layer "F.Cu")
			(hatch none 0.5)
			(connect_pads
				(clearance 0)
			)
			(min_thickness 0.25)
			(keepout
				(tracks not_allowed)
				(vias allowed)
				(pads allowed)
				(copperpour not_allowed)
				(footprints allowed)
			)
			(placement
				(enabled no)
				(sheetname "")
			)
			(fill
				(thermal_gap 0.5)
				(thermal_bridge_width 0.5)
				(island_removal_mode 0)
			)
			(polygon
				(pts
					(xy 125.130814 -287.899094) (xy 125.130814 -287.149794) (xy 120.13057 -287.149794) (xy 120.13057 -287.899094)
					(xy 120.420892 -287.899094) (xy 120.420892 -287.443418) (xy 124.840492 -287.443418) (xy 124.840492 -287.899094)
				)
			)
		)
	)
)
